# Barreleye-G2_Tri-mode Expander-DVT-X01-SKU-BOM-X07-20171222_Final.xls.xlsx — TLA (bom)
| FOXCONN TECHNOLOGY GROUP |  |  |  |  |  |  |  |  |  |
| BILL OF MATERIAL |  |  |  |  |  |  |  |  |  |
| AA P/N | 1A42NC400-600-1 | CUSTOMER | <name> | Customer P/N | N/A | Product Code |  |  |  |
| AA P/N | 1A42NC400-600-2 |  |  |  |  |  |  |  |  |
| AA P/N | 1A42NC400-600-3 |  |  |  |  |  |  |  |  |
| PWA P/N |  | PWA DESCRIPTION | Tri-mode Expander Board |  |  | PWA REV | DVT-X01 | Prepared By SE |  |
| Item | FOXCONN P/N | Customer P/N | Part Description | Manufacturer  Full Name | Manufacturer  Part Number | Qty | RoHS Status | Location | Remark |
| 1 | 7J-004-938 |  | L6 LABEL ( 12.7*11.1mm) | FOXCONN / EPD1 | 7J-004-938 | 1 | G |  |  |
| 2 | 48011V500-600-G |  | Heatsink,AL6063-T5,G,PHCM79X02012 | FOXCONN / T1 | PHCM79X02012 | 1 | G |  | Rev.X00 |
|  | 480120400-21M-G |  | Heatsink,AL6063-T5,G,0RJLK0000H | Forcecon | 0RJLK0000H |  | G |  | Rev.X00 |
| 3 | 480120S00-600-G |  | PLX9797 HSK | Foxconn/T1 | PHCN58GX0012 | 1 | G |  | Rev.X1 |
